(kicad_pcb
	(version 20260206)
	(generator "pcbnew")
	(generator_version "10.0")
	(general
		(thickness 1.6)
		(legacy_teardrops no)
	)
	(paper "A4")
	(title_block
		(title "04192023_DAF0TMB3IC0_F0TG_MB_C_brd_V02_OCP.brd")
		(comment 1 "Grand Teton / footprint 4371 of 8354 (J26), pads 1-113 of 291")
	)
	(layers
		(0 "F.Cu" signal "TOP")
		(4 "In1.Cu" signal "GND")
		(6 "In2.Cu" signal "IN1")
		(8 "In3.Cu" signal "GND1")
		(10 "In4.Cu" signal "IN2")
		(12 "In5.Cu" signal "GND2")
		(14 "In6.Cu" signal "IN3")
		(16 "In7.Cu" signal "GND3")
		(18 "In8.Cu" signal "VCC")
		(20 "In9.Cu" signal "VCC1")
		(22 "In10.Cu" signal "GND4")
		(24 "In11.Cu" signal "IN4")
		(26 "In12.Cu" signal "GND5")
		(28 "In13.Cu" signal "IN5")
		(30 "In14.Cu" signal "GND6")
		(32 "In15.Cu" signal "IN6")
		(34 "In16.Cu" signal "GND7")
		(2 "B.Cu" signal "BOTTOM")
		(9 "F.Adhes" user "F.Adhesive")
		(11 "B.Adhes" user "B.Adhesive")
		(13 "F.Paste" user "Package Geometry/Pastemask Top")
		(15 "B.Paste" user "Package Geometry/Pastemask Bottom")
		(5 "F.SilkS" user "Ref Des/Silkscreen Top")
		(7 "B.SilkS" user "Ref Des/Silkscreen Bottom")
		(1 "F.Mask" user "Board Geometry/Soldermask Top")
		(3 "B.Mask" user "Board Geometry/Soldermask Bottom")
		(17 "Dwgs.User" user "User.Drawings")
		(19 "Cmts.User" user "User.Comments")
		(21 "Eco1.User" user "User.Eco1")
		(23 "Eco2.User" user "User.Eco2")
		(25 "Edge.Cuts" user "Board Geometry/Outline")
		(27 "Margin" user)
		(31 "F.CrtYd" user "Package Geometry/Place Bound Top")
		(29 "B.CrtYd" user "Package Geometry/Place Bound Bottom")
		(35 "F.Fab" user "Ref Des/Assembly Top")
		(33 "B.Fab" user "Ref Des/Assembly Bottom")
	)
	(footprint ""
		(layer "F.Cu")
		(at 49.834038 -255.560322 180)
		(property "Reference" "J26"
			(at -0.703326 -82.357722 0)
			(unlocked yes)
			(layer "F.SilkS")
			(effects
				(font
					(size 0.7874 0.5842)
					(thickness 0.1524)
				)
			)
		)
		(property "Value" ""
			(at 0 0 180)
			(layer "F.Fab")
			(effects
				(font
					(size 1.27 1.27)
				)
			)
		)
		(duplicate_pad_numbers_are_jumpers no)
		(pad "1" smd rect
			(at -2.050034 -63.324994 90)
			(size 0.519938 1.4986)
			(layers "F.Cu" "F.Mask" "F.Paste")
			(net "P12V_MEM_CPU1")
		)
		(pad "2" smd rect
			(at -2.050034 -62.47511 90)
			(size 0.519938 1.4986)
			(layers "F.Cu" "F.Mask" "F.Paste")
			(net "Net_2270")
		)
		(pad "3" smd rect
			(at -2.050034 -61.624972 90)
			(size 0.519938 1.4986)
			(layers "F.Cu" "F.Mask" "F.Paste")
			(net "P3V3_AUX")
		)
		(pad "4" smd rect
			(at -2.050034 -60.775088 90)
			(size 0.519938 1.4986)
			(layers "F.Cu" "F.Mask" "F.Paste")
			(net "I3C_SPD_DDRB_CPU1_SCL")
		)
		(pad "5" smd rect
			(at -2.050034 -59.92495 90)
			(size 0.519938 1.4986)
			(layers "F.Cu" "F.Mask" "F.Paste")
			(net "I3C_SPD_DDRB_CPU1_SDA")
		)
		(pad "6" smd rect
			(at -2.050034 -59.075066 90)
			(size 0.519938 1.4986)
			(layers "F.Cu" "F.Mask" "F.Paste")
			(net "GND")
		)
		(pad "7" smd rect
			(at -2.050034 -58.224928 90)
			(size 0.519938 1.4986)
			(layers "F.Cu" "F.Mask" "F.Paste")
			(net "M_B_CPU1_SA_DQ<0>")
		)
		(pad "8" smd rect
			(at -2.050034 -57.375044 90)
			(size 0.519938 1.4986)
			(layers "F.Cu" "F.Mask" "F.Paste")
			(net "GND")
		)
		(pad "9" smd rect
			(at -2.050034 -56.524906 90)
			(size 0.519938 1.4986)
			(layers "F.Cu" "F.Mask" "F.Paste")
			(net "M_B_CPU1_SA_DQ<1>")
		)
		(pad "10" smd rect
			(at -2.050034 -55.675022 90)
			(size 0.519938 1.4986)
			(layers "F.Cu" "F.Mask" "F.Paste")
			(net "GND")
		)
		(pad "11" smd rect
			(at -2.050034 -54.824884 90)
			(size 0.519938 1.4986)
			(layers "F.Cu" "F.Mask" "F.Paste")
			(net "M_B_CPU1_SA_DQS_DP<0>")
		)
		(pad "12" smd rect
			(at -2.050034 -53.975 90)
			(size 0.519938 1.4986)
			(layers "F.Cu" "F.Mask" "F.Paste")
			(net "M_B_CPU1_SA_DQS_DN<0>")
		)
		(pad "13" smd rect
			(at -2.050034 -53.125116 90)
			(size 0.519938 1.4986)
			(layers "F.Cu" "F.Mask" "F.Paste")
			(net "GND")
		)
		(pad "14" smd rect
			(at -2.050034 -52.274978 90)
			(size 0.519938 1.4986)
			(layers "F.Cu" "F.Mask" "F.Paste")
			(net "M_B_CPU1_SA_DQ<4>")
		)
		(pad "15" smd rect
			(at -2.050034 -51.425094 90)
			(size 0.519938 1.4986)
			(layers "F.Cu" "F.Mask" "F.Paste")
			(net "GND")
		)
		(pad "16" smd rect
			(at -2.050034 -50.574956 90)
			(size 0.519938 1.4986)
			(layers "F.Cu" "F.Mask" "F.Paste")
			(net "M_B_CPU1_SA_DQ<5>")
		)
		(pad "17" smd rect
			(at -2.050034 -49.725072 90)
			(size 0.519938 1.4986)
			(layers "F.Cu" "F.Mask" "F.Paste")
			(net "GND")
		)
		(pad "18" smd rect
			(at -2.050034 -48.874934 90)
			(size 0.519938 1.4986)
			(layers "F.Cu" "F.Mask" "F.Paste")
			(net "M_B_CPU1_SA_DQ<8>")
		)
		(pad "19" smd rect
			(at -2.050034 -48.02505 90)
			(size 0.519938 1.4986)
			(layers "F.Cu" "F.Mask" "F.Paste")
			(net "GND")
		)
		(pad "20" smd rect
			(at -2.050034 -47.174912 90)
			(size 0.519938 1.4986)
			(layers "F.Cu" "F.Mask" "F.Paste")
			(net "M_B_CPU1_SA_DQ<9>")
		)
		(pad "21" smd rect
			(at -2.050034 -46.325028 90)
			(size 0.519938 1.4986)
			(layers "F.Cu" "F.Mask" "F.Paste")
			(net "GND")
		)
		(pad "22" smd rect
			(at -2.050034 -45.47489 90)
			(size 0.519938 1.4986)
			(layers "F.Cu" "F.Mask" "F.Paste")
			(net "M_B_CPU1_SA_DQS_DP<1>")
		)
		(pad "23" smd rect
			(at -2.050034 -44.625006 90)
			(size 0.519938 1.4986)
			(layers "F.Cu" "F.Mask" "F.Paste")
			(net "M_B_CPU1_SA_DQS_DN<1>")
		)
		(pad "24" smd rect
			(at -2.050034 -43.775122 90)
			(size 0.519938 1.4986)
			(layers "F.Cu" "F.Mask" "F.Paste")
			(net "GND")
		)
		(pad "25" smd rect
			(at -2.050034 -42.924984 90)
			(size 0.519938 1.4986)
			(layers "F.Cu" "F.Mask" "F.Paste")
			(net "M_B_CPU1_SA_DQ<12>")
		)
		(pad "26" smd rect
			(at -2.050034 -42.0751 90)
			(size 0.519938 1.4986)
			(layers "F.Cu" "F.Mask" "F.Paste")
			(net "GND")
		)
		(pad "27" smd rect
			(at -2.050034 -41.224962 90)
			(size 0.519938 1.4986)
			(layers "F.Cu" "F.Mask" "F.Paste")
			(net "M_B_CPU1_SA_DQ<13>")
		)
		(pad "28" smd rect
			(at -2.050034 -40.375078 90)
			(size 0.519938 1.4986)
			(layers "F.Cu" "F.Mask" "F.Paste")
			(net "GND")
		)
		(pad "29" smd rect
			(at -2.050034 -39.52494 90)
			(size 0.519938 1.4986)
			(layers "F.Cu" "F.Mask" "F.Paste")
			(net "M_B_CPU1_SA_DQ<16>")
		)
		(pad "30" smd rect
			(at -2.050034 -38.675056 90)
			(size 0.519938 1.4986)
			(layers "F.Cu" "F.Mask" "F.Paste")
			(net "GND")
		)
		(pad "31" smd rect
			(at -2.050034 -37.824918 90)
			(size 0.519938 1.4986)
			(layers "F.Cu" "F.Mask" "F.Paste")
			(net "M_B_CPU1_SA_DQ<17>")
		)
		(pad "32" smd rect
			(at -2.050034 -36.975034 90)
			(size 0.519938 1.4986)
			(layers "F.Cu" "F.Mask" "F.Paste")
			(net "GND")
		)
		(pad "33" smd rect
			(at -2.050034 -36.124896 90)
			(size 0.519938 1.4986)
			(layers "F.Cu" "F.Mask" "F.Paste")
			(net "M_B_CPU1_SA_DQS_DP<2>")
		)
		(pad "34" smd rect
			(at -2.050034 -35.275012 90)
			(size 0.519938 1.4986)
			(layers "F.Cu" "F.Mask" "F.Paste")
			(net "M_B_CPU1_SA_DQS_DN<2>")
		)
		(pad "35" smd rect
			(at -2.050034 -34.425128 90)
			(size 0.519938 1.4986)
			(layers "F.Cu" "F.Mask" "F.Paste")
			(net "GND")
		)
		(pad "36" smd rect
			(at -2.050034 -33.57499 90)
			(size 0.519938 1.4986)
			(layers "F.Cu" "F.Mask" "F.Paste")
			(net "M_B_CPU1_SA_DQ<20>")
		)
		(pad "37" smd rect
			(at -2.050034 -32.725106 90)
			(size 0.519938 1.4986)
			(layers "F.Cu" "F.Mask" "F.Paste")
			(net "GND")
		)
		(pad "38" smd rect
			(at -2.050034 -31.874968 90)
			(size 0.519938 1.4986)
			(layers "F.Cu" "F.Mask" "F.Paste")
			(net "M_B_CPU1_SA_DQ<21>")
		)
		(pad "39" smd rect
			(at -2.050034 -31.025084 90)
			(size 0.519938 1.4986)
			(layers "F.Cu" "F.Mask" "F.Paste")
			(net "GND")
		)
		(pad "40" smd rect
			(at -2.050034 -30.174946 90)
			(size 0.519938 1.4986)
			(layers "F.Cu" "F.Mask" "F.Paste")
			(net "M_B_CPU1_SA_DQ<24>")
		)
		(pad "41" smd rect
			(at -2.050034 -29.325062 90)
			(size 0.519938 1.4986)
			(layers "F.Cu" "F.Mask" "F.Paste")
			(net "GND")
		)
		(pad "42" smd rect
			(at -2.050034 -28.474924 90)
			(size 0.519938 1.4986)
			(layers "F.Cu" "F.Mask" "F.Paste")
			(net "M_B_CPU1_SA_DQ<25>")
		)
		(pad "43" smd rect
			(at -2.050034 -27.62504 90)
			(size 0.519938 1.4986)
			(layers "F.Cu" "F.Mask" "F.Paste")
			(net "GND")
		)
		(pad "44" smd rect
			(at -2.050034 -26.774902 90)
			(size 0.519938 1.4986)
			(layers "F.Cu" "F.Mask" "F.Paste")
			(net "M_B_CPU1_SA_DQS_DP<3>")
		)
		(pad "45" smd rect
			(at -2.050034 -25.925018 90)
			(size 0.519938 1.4986)
			(layers "F.Cu" "F.Mask" "F.Paste")
			(net "M_B_CPU1_SA_DQS_DN<3>")
		)
		(pad "46" smd rect
			(at -2.050034 -25.07488 90)
			(size 0.519938 1.4986)
			(layers "F.Cu" "F.Mask" "F.Paste")
			(net "GND")
		)
		(pad "47" smd rect
			(at -2.050034 -24.224996 90)
			(size 0.519938 1.4986)
			(layers "F.Cu" "F.Mask" "F.Paste")
			(net "M_B_CPU1_SA_DQ<28>")
		)
		(pad "48" smd rect
			(at -2.050034 -23.375112 90)
			(size 0.519938 1.4986)
			(layers "F.Cu" "F.Mask" "F.Paste")
			(net "GND")
		)
		(pad "49" smd rect
			(at -2.050034 -22.524974 90)
			(size 0.519938 1.4986)
			(layers "F.Cu" "F.Mask" "F.Paste")
			(net "M_B_CPU1_SA_DQ<29>")
		)
		(pad "50" smd rect
			(at -2.050034 -21.67509 90)
			(size 0.519938 1.4986)
			(layers "F.Cu" "F.Mask" "F.Paste")
			(net "GND")
		)
		(pad "51" smd rect
			(at -2.050034 -20.824952 90)
			(size 0.519938 1.4986)
			(layers "F.Cu" "F.Mask" "F.Paste")
			(net "M_B_CPU1_SA_CB<0>")
		)
		(pad "52" smd rect
			(at -2.050034 -19.975068 90)
			(size 0.519938 1.4986)
			(layers "F.Cu" "F.Mask" "F.Paste")
			(net "GND")
		)
		(pad "53" smd rect
			(at -2.050034 -19.12493 90)
			(size 0.519938 1.4986)
			(layers "F.Cu" "F.Mask" "F.Paste")
			(net "M_B_CPU1_SA_CB<1>")
		)
		(pad "54" smd rect
			(at -2.050034 -18.275046 90)
			(size 0.519938 1.4986)
			(layers "F.Cu" "F.Mask" "F.Paste")
			(net "GND")
		)
		(pad "55" smd rect
			(at -2.050034 -17.424908 90)
			(size 0.519938 1.4986)
			(layers "F.Cu" "F.Mask" "F.Paste")
			(net "M_B_CPU1_SA_DQS_DP<4>")
		)
		(pad "56" smd rect
			(at -2.050034 -16.575024 90)
			(size 0.519938 1.4986)
			(layers "F.Cu" "F.Mask" "F.Paste")
			(net "M_B_CPU1_SA_DQS_DN<4>")
		)
		(pad "57" smd rect
			(at -2.050034 -15.724886 90)
			(size 0.519938 1.4986)
			(layers "F.Cu" "F.Mask" "F.Paste")
			(net "GND")
		)
		(pad "58" smd rect
			(at -2.050034 -14.875002 90)
			(size 0.519938 1.4986)
			(layers "F.Cu" "F.Mask" "F.Paste")
			(net "M_B_CPU1_SA_CB<4>")
		)
		(pad "59" smd rect
			(at -2.050034 -14.025118 90)
			(size 0.519938 1.4986)
			(layers "F.Cu" "F.Mask" "F.Paste")
			(net "GND")
		)
		(pad "60" smd rect
			(at -2.050034 -13.17498 90)
			(size 0.519938 1.4986)
			(layers "F.Cu" "F.Mask" "F.Paste")
			(net "M_B_CPU1_SA_CB<5>")
		)
		(pad "61" smd rect
			(at -2.050034 -12.325096 90)
			(size 0.519938 1.4986)
			(layers "F.Cu" "F.Mask" "F.Paste")
			(net "GND")
		)
		(pad "62" smd rect
			(at -2.050034 -11.474958 90)
			(size 0.519938 1.4986)
			(layers "F.Cu" "F.Mask" "F.Paste")
			(net "M_B_CPU1_ALERT_N")
		)
		(pad "63" smd rect
			(at -2.050034 -10.625074 90)
			(size 0.519938 1.4986)
			(layers "F.Cu" "F.Mask" "F.Paste")
			(net "GND")
		)
		(pad "64" smd rect
			(at -2.050034 -9.774936 90)
			(size 0.519938 1.4986)
			(layers "F.Cu" "F.Mask" "F.Paste")
			(net "M_B_CPU1_SA_CS_N<0>")
		)
		(pad "65" smd rect
			(at -2.050034 -8.925052 90)
			(size 0.519938 1.4986)
			(layers "F.Cu" "F.Mask" "F.Paste")
			(net "GND")
		)
		(pad "66" smd rect
			(at -2.050034 -8.074914 90)
			(size 0.519938 1.4986)
			(layers "F.Cu" "F.Mask" "F.Paste")
			(net "M_B_CPU1_SA_CA<0>")
		)
		(pad "67" smd rect
			(at -2.050034 -7.22503 90)
			(size 0.519938 1.4986)
			(layers "F.Cu" "F.Mask" "F.Paste")
			(net "GND")
		)
		(pad "68" smd rect
			(at -2.050034 -6.374892 90)
			(size 0.519938 1.4986)
			(layers "F.Cu" "F.Mask" "F.Paste")
			(net "M_B_CPU1_SA_CA<2>")
		)
		(pad "69" smd rect
			(at -2.050034 -5.525008 90)
			(size 0.519938 1.4986)
			(layers "F.Cu" "F.Mask" "F.Paste")
			(net "GND")
		)
		(pad "70" smd rect
			(at -2.050034 -4.675124 90)
			(size 0.519938 1.4986)
			(layers "F.Cu" "F.Mask" "F.Paste")
			(net "M_B_CPU1_SA_CA<4>")
		)
		(pad "71" smd rect
			(at -2.050034 -3.824986 90)
			(size 0.519938 1.4986)
			(layers "F.Cu" "F.Mask" "F.Paste")
			(net "GND")
		)
		(pad "72" smd rect
			(at -2.050034 -2.975102 90)
			(size 0.519938 1.4986)
			(layers "F.Cu" "F.Mask" "F.Paste")
			(net "M_B_CPU1_SA_CA<6>")
		)
		(pad "73" smd rect
			(at -2.050034 -2.124964 90)
			(size 0.519938 1.4986)
			(layers "F.Cu" "F.Mask" "F.Paste")
			(net "GND")
		)
		(pad "74" smd rect
			(at -2.050034 -1.27508 90)
			(size 0.519938 1.4986)
			(layers "F.Cu" "F.Mask" "F.Paste")
			(net "M_B_CPU1_SA_PAR")
		)
		(pad "75" smd rect
			(at -2.050034 -0.424942 90)
			(size 0.519938 1.4986)
			(layers "F.Cu" "F.Mask" "F.Paste")
			(net "GND")
		)
		(pad "76" smd rect
			(at -2.050034 5.525008 90)
			(size 0.519938 1.4986)
			(layers "F.Cu" "F.Mask" "F.Paste")
			(net "M_B_CPU1_SB_CA<0>")
		)
		(pad "77" smd rect
			(at -2.050034 6.374892 90)
			(size 0.519938 1.4986)
			(layers "F.Cu" "F.Mask" "F.Paste")
			(net "GND")
		)
		(pad "78" smd rect
			(at -2.050034 7.22503 90)
			(size 0.519938 1.4986)
			(layers "F.Cu" "F.Mask" "F.Paste")
			(net "M_B_CPU1_SB_CA<2>")
		)
		(pad "79" smd rect
			(at -2.050034 8.074914 90)
			(size 0.519938 1.4986)
			(layers "F.Cu" "F.Mask" "F.Paste")
			(net "GND")
		)
		(pad "80" smd rect
			(at -2.050034 8.925052 90)
			(size 0.519938 1.4986)
			(layers "F.Cu" "F.Mask" "F.Paste")
			(net "M_B_CPU1_SB_CA<4>")
		)
		(pad "81" smd rect
			(at -2.050034 9.774936 90)
			(size 0.519938 1.4986)
			(layers "F.Cu" "F.Mask" "F.Paste")
			(net "GND")
		)
		(pad "82" smd rect
			(at -2.050034 10.625074 90)
			(size 0.519938 1.4986)
			(layers "F.Cu" "F.Mask" "F.Paste")
			(net "M_B_CPU1_SB_CA<6>")
		)
		(pad "83" smd rect
			(at -2.050034 11.474958 90)
			(size 0.519938 1.4986)
			(layers "F.Cu" "F.Mask" "F.Paste")
			(net "GND")
		)
		(pad "84" smd rect
			(at -2.050034 12.325096 90)
			(size 0.519938 1.4986)
			(layers "F.Cu" "F.Mask" "F.Paste")
			(net "M_B_CPU1_SB_CS_N<0>")
		)
		(pad "85" smd rect
			(at -2.050034 13.17498 90)
			(size 0.519938 1.4986)
			(layers "F.Cu" "F.Mask" "F.Paste")
			(net "GND")
		)
		(pad "86" smd rect
			(at -2.050034 14.025118 90)
			(size 0.519938 1.4986)
			(layers "F.Cu" "F.Mask" "F.Paste")
			(net "M_B_CPU1_SA_RSP<0>")
		)
		(pad "87" smd rect
			(at -2.050034 14.875002 90)
			(size 0.519938 1.4986)
			(layers "F.Cu" "F.Mask" "F.Paste")
			(net "M_B_CPU1_SB_RSP<0>")
		)
		(pad "88" smd rect
			(at -2.050034 15.724886 90)
			(size 0.519938 1.4986)
			(layers "F.Cu" "F.Mask" "F.Paste")
			(net "GND")
		)
		(pad "89" smd rect
			(at -2.050034 16.575024 90)
			(size 0.519938 1.4986)
			(layers "F.Cu" "F.Mask" "F.Paste")
			(net "M_B_CPU1_SB_CB<4>")
		)
		(pad "90" smd rect
			(at -2.050034 17.424908 90)
			(size 0.519938 1.4986)
			(layers "F.Cu" "F.Mask" "F.Paste")
			(net "GND")
		)
		(pad "91" smd rect
			(at -2.050034 18.275046 90)
			(size 0.519938 1.4986)
			(layers "F.Cu" "F.Mask" "F.Paste")
			(net "M_B_CPU1_SB_CB<5>")
		)
		(pad "92" smd rect
			(at -2.050034 19.12493 90)
			(size 0.519938 1.4986)
			(layers "F.Cu" "F.Mask" "F.Paste")
			(net "GND")
		)
		(pad "93" smd rect
			(at -2.050034 19.975068 90)
			(size 0.519938 1.4986)
			(layers "F.Cu" "F.Mask" "F.Paste")
			(net "M_B_CPU1_SB_DQS_DP<9>")
		)
		(pad "94" smd rect
			(at -2.050034 20.824952 90)
			(size 0.519938 1.4986)
			(layers "F.Cu" "F.Mask" "F.Paste")
			(net "M_B_CPU1_SB_DQS_DN<9>")
		)
		(pad "95" smd rect
			(at -2.050034 21.67509 90)
			(size 0.519938 1.4986)
			(layers "F.Cu" "F.Mask" "F.Paste")
			(net "GND")
		)
		(pad "96" smd rect
			(at -2.050034 22.524974 90)
			(size 0.519938 1.4986)
			(layers "F.Cu" "F.Mask" "F.Paste")
			(net "M_B_CPU1_SB_CB<0>")
		)
		(pad "97" smd rect
			(at -2.050034 23.375112 90)
			(size 0.519938 1.4986)
			(layers "F.Cu" "F.Mask" "F.Paste")
			(net "GND")
		)
		(pad "98" smd rect
			(at -2.050034 24.224996 90)
			(size 0.519938 1.4986)
			(layers "F.Cu" "F.Mask" "F.Paste")
			(net "M_B_CPU1_SB_CB<1>")
		)
		(pad "99" smd rect
			(at -2.050034 25.07488 90)
			(size 0.519938 1.4986)
			(layers "F.Cu" "F.Mask" "F.Paste")
			(net "GND")
		)
		(pad "100" smd rect
			(at -2.050034 25.925018 90)
			(size 0.519938 1.4986)
			(layers "F.Cu" "F.Mask" "F.Paste")
			(net "M_B_CPU1_SB_DQ<0>")
		)
		(pad "101" smd rect
			(at -2.050034 26.774902 90)
			(size 0.519938 1.4986)
			(layers "F.Cu" "F.Mask" "F.Paste")
			(net "GND")
		)
		(pad "102" smd rect
			(at -2.050034 27.62504 90)
			(size 0.519938 1.4986)
			(layers "F.Cu" "F.Mask" "F.Paste")
			(net "M_B_CPU1_SB_DQ<1>")
		)
		(pad "103" smd rect
			(at -2.050034 28.474924 90)
			(size 0.519938 1.4986)
			(layers "F.Cu" "F.Mask" "F.Paste")
			(net "GND")
		)
		(pad "104" smd rect
			(at -2.050034 29.325062 90)
			(size 0.519938 1.4986)
			(layers "F.Cu" "F.Mask" "F.Paste")
			(net "M_B_CPU1_SB_DQS_DP<0>")
		)
		(pad "105" smd rect
			(at -2.050034 30.174946 90)
			(size 0.519938 1.4986)
			(layers "F.Cu" "F.Mask" "F.Paste")
			(net "M_B_CPU1_SB_DQS_DN<0>")
		)
		(pad "106" smd rect
			(at -2.050034 31.025084 90)
			(size 0.519938 1.4986)
			(layers "F.Cu" "F.Mask" "F.Paste")
			(net "GND")
		)
		(pad "107" smd rect
			(at -2.050034 31.874968 90)
			(size 0.519938 1.4986)
			(layers "F.Cu" "F.Mask" "F.Paste")
			(net "M_B_CPU1_SB_DQ<4>")
		)
		(pad "108" smd rect
			(at -2.050034 32.725106 90)
			(size 0.519938 1.4986)
			(layers "F.Cu" "F.Mask" "F.Paste")
			(net "GND")
		)
		(pad "109" smd rect
			(at -2.050034 33.57499 90)
			(size 0.519938 1.4986)
			(layers "F.Cu" "F.Mask" "F.Paste")
			(net "M_B_CPU1_SB_DQ<5>")
		)
		(pad "110" smd rect
			(at -2.050034 34.425128 90)
			(size 0.519938 1.4986)
			(layers "F.Cu" "F.Mask" "F.Paste")
			(net "GND")
		)
		(pad "111" smd rect
			(at -2.050034 35.275012 90)
			(size 0.519938 1.4986)
			(layers "F.Cu" "F.Mask" "F.Paste")
			(net "M_B_CPU1_SB_DQ<8>")
		)
		(pad "112" smd rect
			(at -2.050034 36.124896 90)
			(size 0.519938 1.4986)
			(layers "F.Cu" "F.Mask" "F.Paste")
			(net "GND")
		)
		(pad "113" smd rect
			(at -2.050034 36.975034 90)
			(size 0.519938 1.4986)
			(layers "F.Cu" "F.Mask" "F.Paste")
			(net "M_B_CPU1_SB_DQ<9>")
		)
	)
)
